# BASEBOARD_FAB2 (Tioga Pass) — schematic netlist excerpt (pin names and nets, part order shuffled) for the footprints in the layout excerpt that follows; sources: Cadence DE-HDL packaged netlist, KiCad conversion of Wiwynn_Tioga_Pass_MB.brd

C4C8  CAP  0.220UF 16V 10% X7R  pkg 0402  page 205 : A = VR_PVSA_CPU0_BOOT ; B = VR_PVSA_CPU0_PHASE
C6D7  CAP_A  22.0UF 4V 20% X6S  pkg 0603V  page 42 : A = PVCCIO_CPU0 ; B = GND
R9F29  RES  4.75K 1% CHIP  pkg 0402  page 151 : A = P1V2_AUX_BMC ; B = RST_BMC_DDR3_R_N

(kicad_pcb
	(version 20260206)
	(generator "pcbnew")
	(generator_version "10.0")
	(general
		(thickness 1.6)
		(legacy_teardrops no)
	)
	(paper "A4")
	(title_block
		(title "Wiwynn_Tioga_Pass_MB.brd")
		(comment 1 "Tioga Pass / footprints 1732-1734 of 4770")
	)
	(layers
		(0 "F.Cu" signal "TOP")
		(4 "In1.Cu" signal "L2GND")
		(6 "In2.Cu" signal "L3")
		(8 "In3.Cu" signal "L4GND")
		(10 "In4.Cu" signal "L5")
		(12 "In5.Cu" signal "L6GND")
		(14 "In6.Cu" signal "L7VCC")
		(16 "In7.Cu" signal "L8VCC")
		(18 "In8.Cu" signal "L9GND")
		(20 "In9.Cu" signal "L10")
		(22 "In10.Cu" signal "L11GND")
		(24 "In11.Cu" signal "L12")
		(26 "In12.Cu" signal "L13GND")
		(2 "B.Cu" signal "BOTTOM")
		(9 "F.Adhes" user "F.Adhesive")
		(11 "B.Adhes" user "B.Adhesive")
		(13 "F.Paste" user "Package Geometry/Pastemask Top")
		(15 "B.Paste" user "Package Geometry/Pastemask Bottom")
		(5 "F.SilkS" user "Ref Des/Silkscreen Top")
		(7 "B.SilkS" user "Ref Des/Silkscreen Bottom")
		(1 "F.Mask" user "Board Geometry/Soldermask Top")
		(3 "B.Mask" user "Board Geometry/Soldermask Bottom")
		(17 "Dwgs.User" user "User.Drawings")
		(19 "Cmts.User" user "User.Comments")
		(21 "Eco1.User" user "User.Eco1")
		(23 "Eco2.User" user "User.Eco2")
		(25 "Edge.Cuts" user "Board Geometry/Outline")
		(27 "Margin" user)
		(31 "F.CrtYd" user "Package Geometry/Place Bound Top")
		(29 "B.CrtYd" user "Package Geometry/Place Bound Bottom")
		(35 "F.Fab" user "Ref Des/Assembly Top")
		(33 "B.Fab" user "Ref Des/Assembly Bottom")
	)
	(footprint ""
		(layer "F.Cu")
		(at 453.3265 -32.131 90)
		(property "Reference" "R9F29"
			(at 0 0 90)
			(layer "F.SilkS")
			(hide yes)
			(effects
				(font
					(size 1.27 1.27)
				)
			)
		)
		(property "Value" ""
			(at 0 0 90)
			(layer "F.Fab")
			(effects
				(font
					(size 1.27 1.27)
				)
			)
		)
		(duplicate_pad_numbers_are_jumpers no)
		(fp_poly
			(pts
				(xy -0.2794 -0.1016) (xy 0.2794 -0.1016) (xy 0.2794 0.9906) (xy -0.2794 0.9906)
			)
			(stroke
				(width 0)
				(type default)
			)
			(fill no)
			(layer "F.CrtYd")
		)
		(fp_line
			(start 0.2794 -0.1016)
			(end -0.2794 -0.1016)
			(stroke
				(width 0.1)
				(type default)
			)
			(layer "F.Fab")
		)
		(fp_line
			(start -0.2794 -0.1016)
			(end -0.2794 0.9906)
			(stroke
				(width 0.1)
				(type default)
			)
			(layer "F.Fab")
		)
		(fp_line
			(start 0.2794 0.9906)
			(end 0.2794 -0.1016)
			(stroke
				(width 0.1)
				(type default)
			)
			(layer "F.Fab")
		)
		(fp_line
			(start -0.2794 0.9906)
			(end 0.2794 0.9906)
			(stroke
				(width 0.1)
				(type default)
			)
			(layer "F.Fab")
		)
		(pad "1" smd rect
			(at 0 0 90)
			(size 0.508 0.508)
			(layers "F.Cu" "F.Mask" "F.Paste")
			(net "P1V2_AUX_BMC")
		)
		(pad "2" smd rect
			(at 0 0.889 90)
			(size 0.508 0.508)
			(layers "F.Cu" "F.Mask" "F.Paste")
			(net "RST_BMC_DDR3_R_N")
		)
		(zone
			(layer "F.Cu")
			(hatch none 0.5)
			(connect_pads
				(clearance 0)
			)
			(min_thickness 0.25)
			(keepout
				(tracks allowed)
				(vias not_allowed)
				(pads allowed)
				(copperpour not_allowed)
				(footprints allowed)
			)
			(placement
				(enabled no)
				(sheetname "")
			)
			(fill
				(thermal_gap 0.5)
				(thermal_bridge_width 0.5)
				(island_removal_mode 0)
			)
			(polygon
				(pts
					(xy 453.5805 -31.877) (xy 453.5805 -32.385) (xy 453.9615 -32.385) (xy 453.9615 -31.877)
				)
			)
		)
		(zone
			(layer "F.Cu")
			(hatch none 0.5)
			(connect_pads
				(clearance 0)
			)
			(min_thickness 0.25)
			(keepout
				(tracks not_allowed)
				(vias allowed)
				(pads allowed)
				(copperpour not_allowed)
				(footprints allowed)
			)
			(placement
				(enabled no)
				(sheetname "")
			)
			(fill
				(thermal_gap 0.5)
				(thermal_bridge_width 0.5)
				(island_removal_mode 0)
			)
			(polygon
				(pts
					(xy 453.9615 -31.877) (xy 453.9615 -32.385) (xy 453.5805 -32.385) (xy 453.5805 -31.877)
				)
			)
		)
	)
	(footprint ""
		(layer "F.Cu")
		(at 279.672034 -77.382116)
		(property "Reference" "C6D7"
			(at 0 0 0)
			(layer "F.SilkS")
			(hide yes)
			(effects
				(font
					(size 1.27 1.27)
				)
			)
		)
		(property "Value" ""
			(at 0 0 0)
			(layer "F.Fab")
			(effects
				(font
					(size 1.27 1.27)
				)
			)
		)
		(duplicate_pad_numbers_are_jumpers no)
		(fp_poly
			(pts
				(xy -0.4953 -0.2032) (xy 0.4953 -0.2032) (xy 0.4953 1.6002) (xy -0.4953 1.6002)
			)
			(stroke
				(width 0)
				(type default)
			)
			(fill no)
			(layer "F.CrtYd")
		)
		(fp_line
			(start -0.4953 -0.2032)
			(end 0.4953 -0.2032)
			(stroke
				(width 0.1)
				(type default)
			)
			(layer "F.Fab")
		)
		(fp_line
			(start -0.4953 1.6002)
			(end -0.4953 -0.2032)
			(stroke
				(width 0.1)
				(type default)
			)
			(layer "F.Fab")
		)
		(fp_line
			(start 0.4953 -0.2032)
			(end 0.4953 1.6002)
			(stroke
				(width 0.1)
				(type default)
			)
			(layer "F.Fab")
		)
		(fp_line
			(start 0.4953 1.6002)
			(end -0.4953 1.6002)
			(stroke
				(width 0.1)
				(type default)
			)
			(layer "F.Fab")
		)
		(pad "1" smd rect
			(at 0 0)
			(size 0.762 0.889)
			(layers "F.Cu" "F.Mask" "F.Paste")
			(net "PVCCIO_CPU0")
		)
		(pad "2" smd rect
			(at 0 1.397)
			(size 0.762 0.889)
			(layers "F.Cu" "F.Mask" "F.Paste")
			(net "GND")
		)
		(zone
			(layer "F.Cu")
			(hatch none 0.5)
			(connect_pads
				(clearance 0)
			)
			(min_thickness 0.25)
			(keepout
				(tracks not_allowed)
				(vias allowed)
				(pads allowed)
				(copperpour not_allowed)
				(footprints allowed)
			)
			(placement
				(enabled no)
				(sheetname "")
			)
			(fill
				(thermal_gap 0.5)
				(thermal_bridge_width 0.5)
				(island_removal_mode 0)
			)
			(polygon
				(pts
					(xy 279.291034 -76.937616) (xy 280.053034 -76.937616) (xy 280.053034 -76.429616) (xy 279.291034 -76.429616)
				)
			)
		)
	)
	(footprint ""
		(layer "F.Cu")
		(at 193.7512 -99.9236 90)
		(property "Reference" "C4C8"
			(at 0 0 90)
			(layer "F.SilkS")
			(hide yes)
			(effects
				(font
					(size 1.27 1.27)
				)
			)
		)
		(property "Value" ""
			(at 0 0 90)
			(layer "F.Fab")
			(effects
				(font
					(size 1.27 1.27)
				)
			)
		)
		(duplicate_pad_numbers_are_jumpers no)
		(fp_rect
			(start -0.3048 0.9906)
			(end 0.3048 -0.1016)
			(stroke
				(width 0)
				(type default)
			)
			(fill no)
			(layer "F.CrtYd")
		)
		(fp_line
			(start 0.3048 -0.1016)
			(end -0.3048 -0.1016)
			(stroke
				(width 0.1)
				(type default)
			)
			(layer "F.Fab")
		)
		(fp_line
			(start -0.3048 -0.1016)
			(end -0.3048 0.9906)
			(stroke
				(width 0.1)
				(type default)
			)
			(layer "F.Fab")
		)
		(fp_line
			(start 0.3048 0.9906)
			(end 0.3048 -0.1016)
			(stroke
				(width 0.1)
				(type default)
			)
			(layer "F.Fab")
		)
		(fp_line
			(start -0.3048 0.9906)
			(end 0.3048 0.9906)
			(stroke
				(width 0.1)
				(type default)
			)
			(layer "F.Fab")
		)
		(pad "1" smd rect
			(at 0 0 90)
			(size 0.508 0.508)
			(layers "F.Cu" "F.Mask" "F.Paste")
			(net "VR_PVSA_CPU0_BOOT")
		)
		(pad "2" smd rect
			(at 0 0.889 90)
			(size 0.508 0.508)
			(layers "F.Cu" "F.Mask" "F.Paste")
			(net "VR_PVSA_CPU0_PHASE")
		)
		(zone
			(layer "F.Cu")
			(hatch none 0.5)
			(connect_pads
				(clearance 0)
			)
			(min_thickness 0.25)
			(keepout
				(tracks not_allowed)
				(vias allowed)
				(pads allowed)
				(copperpour not_allowed)
				(footprints allowed)
			)
			(placement
				(enabled no)
				(sheetname "")
			)
			(fill
				(thermal_gap 0.5)
				(thermal_bridge_width 0.5)
				(island_removal_mode 0)
			)
			(polygon
				(pts
					(xy 194.3862 -99.6696) (xy 194.3862 -100.1776) (xy 194.0052 -100.1776) (xy 194.0052 -99.6696)
				)
			)
		)
		(zone
			(layer "F.Cu")
			(hatch none 0.5)
			(connect_pads
				(clearance 0)
			)
			(min_thickness 0.25)
			(keepout
				(tracks allowed)
				(vias not_allowed)
				(pads allowed)
				(copperpour not_allowed)
				(footprints allowed)
			)
			(placement
				(enabled no)
				(sheetname "")
			)
			(fill
				(thermal_gap 0.5)
				(thermal_bridge_width 0.5)
				(island_removal_mode 0)
			)
			(polygon
				(pts
					(xy 194.3862 -99.6696) (xy 194.3862 -100.1776) (xy 194.0052 -100.1776) (xy 194.0052 -99.6696)
				)
			)
		)
	)
)
